# SCM (Grand Teton) — schematic parts with pin connectivity, parts 187–349 of 1428; source: Cadence DE-HDL packaged netlist (pstxprt.dat, pstxnet.dat, pstchip.dat)

C192  Q_CAP  0.1UF 25V 10% X7R  pkg 0402  page 26 : 1 = P3V3_AUX ; 2 = GND
C193  Q_CAP  0.1UF 25V 10% X7R  pkg 0402  page 41 : 1 = PVCCA_AUX_PLD ; 2 = GND
C194  Q_CAP  10UF 16V 20% X6S  pkg C0603  page 41 : 1 = P3V3_AUX ; 2 = GND
C195  Q_CAP  1UF 25V 10% X6S  pkg C0402  page 41 : 1 = VCCIO4 ; 2 = GND
C196  Q_CAP  1UF 25V 10% X6S  pkg C0402  page 50 : 1 = P3V3_RTC_AUX ; 2 = GND
C197  Q_CAP  0.1UF 25V 10% X7R  pkg 0402  page 49 : 1 = HDD_LED_P5V_AUX ; 2 = GND
C198  Q_CAP  1UF 25V 10% X6S  pkg C0402  page 50 : 1 = REAR_PWR_BTN_N ; 2 = GND
C199  Q_CAP  1UF 25V 10% X6S  pkg C0402  page 50 : 1 = REAR_ID_RST_BTN_N ; 2 = GND
C200  Q_CAP  0.1UF 25V 10% X7R  pkg 0402  page 50 : 1 = P3V3_AUX ; 2 = GND
C201  Q_CAP  0.1UF 25V 10% X7R  pkg 0402  page 50 : 1 = P3V3_AUX ; 2 = GND
C202  Q_CAP  0.1UF 25V 10% X7R  pkg 0402  page 23 : 1 = P5V_AUX ; 2 = GND
C203  Q_CAP  0.1UF 25V 10% X7R  pkg 0402  page 23 : 1 = P5V_AUX ; 2 = GND
C204  Q_CAP  1UF 16V 10% EMPTY  pkg 0603  page 23 : 1 = CRT_VCC5 ; 2 = GND
C205  Q_CAP  15PF 50V 5% C0G  pkg 0402  page 23 : 1 = V_DACR ; 2 = GND
C206  Q_CAP  15PF 50V 5% C0G  pkg 0402  page 23 : 1 = V_DACG ; 2 = GND
C207  Q_CAP  15PF 50V 5% C0G  pkg 0402  page 23 : 1 = V_DACB ; 2 = GND
C208  Q_CAP  22PF 50V 5% NPO  pkg 0402  page 23 : 1 = V_DACR_IO ; 2 = GND
C209  Q_CAP  18PF 50V 5% C0G  pkg 0402  page 23 : 1 = V_DACG_IO ; 2 = GND
C210  Q_CAP  22PF 50V 5% NPO  pkg 0402  page 23 : 1 = V_DACB_IO ; 2 = GND
C211  Q_CAP  10PF 50V 1% NPO  pkg 0402  page 23 : 1 = V_VGAHS_BUF ; 2 = GND
C212  Q_CAP  10PF 50V 1% NPO  pkg 0402  page 23 : 1 = V_VGAVS_BUF ; 2 = GND
C213  Q_CAP  100PF 50V 5% EMPTY  pkg 0402  page 23 : 1 = V_BMC_LS_DDC_SDA_R ; 2 = GND
C214  Q_CAP  100PF 50V 5% EMPTY  pkg 0402  page 23 : 1 = V_BMC_LS_DDC_SCL_R ; 2 = GND
C215  Q_CAP  10UF 6.3V 20% X6S  pkg C0402  page 32 : 1 = J7_P1 ; 2 = GND
C216  Q_CAP  1UF 25V 10% X6S  pkg C0402  page 41 : 1 = VCCIO3 ; 2 = GND
C217  Q_CAP  0.1UF 25V 10% X7R  pkg 0402  page 32 : 1 = J7_P1 ; 2 = GND
C218  Q_CAP  1UF 25V 10% X6S  pkg C0402  page 41 : 1 = VCCIO5 ; 2 = GND
C219  Q_CAP  0.1UF 25V 10% X7R  pkg 0402  page 29 : 1 = P3V3_AUX ; 2 = GND
C220  Q_CAP  0.1UF 25V 10% X7R  pkg 0402  page 41 : 1 = VCCIO4 ; 2 = GND
C221  Q_CAP  0.1UF 25V 10% X7R  pkg 0402  page 20 : 1 = P1V2_AUX ; 2 = GND
C222  Q_CAP  0.1UF 25V 10% X7R  pkg 0402  page 20 : 1 = P1V2_AUX ; 2 = GND
C223  Q_CAP  4700P 25V 10% EMPTY  pkg C0402  page 22 : 1 = RST_BMC_SRST_BUF_R_N ; 2 = GND
C224  Q_CAP  10UF 6.3V 20% X6S  pkg C0402  page 17 : 1 = PGPPA_BMC_AUX ; 2 = GND
C225  Q_CAP  0.1UF 25V 10% X7R  pkg 0402  page 20 : 1 = P1V2_AUX ; 2 = GND
C226  Q_CAP  1UF 25V 10% X6S  pkg C0402  page 51 : 1 = P12V_AUX ; 2 = GND
C227  Q_CAP  2.2UF 10V 10% X6S  pkg C0402  page 51 : 1 = P3V3_LDO ; 2 = GND
C228  Q_CAP  0.1UF 25V 10% EMPTY  pkg 0402  page 21 : 1 = P3V3_AUX ; 2 = GND
C229  Q_CAP  0.22UF 16V 10% EMPTY  pkg 0402  page 20 : 1 = M_BMC_DDR4_MCLK_C ; 2 = P1V2_AUX
C231  Q_CAP  0.1UF 25V 10% X7R  pkg 0402  page 31 : 1 = P3V3_AUX ; 2 = GND
C234  Q_CAP  22UF 10V 20% EMPTY  pkg C0603  page 21 : 1 = P3V3_AUX ; 2 = GND
C235  Q_CAP  0.1UF 25V 10% EMPTY  pkg 0402  page 21 : 1 = P3V3_AUX ; 2 = GND
C236  Q_CAP  0.1UF 25V 10% X7R  pkg 0402  page 29 : 1 = P3V3_AUX ; 2 = GND
C237  Q_CAP  0.1UF 25V 10% X7R  pkg 0402  page 29 : 1 = P3V3_AUX ; 2 = GND
C238  Q_CAP  0.1UF 25V 10% EMPTY  pkg 0402  page 29 : 1 = USB3_FPNL_TXP ; 2 = USB3_01_TXP_C
C239  Q_CAP  0.1UF 25V 10% EMPTY  pkg 0402  page 29 : 1 = USB3_FPNL_TXN ; 2 = USB3_01_TXN_C
C240  Q_CAP  0.1UF 25V 10% X7R  pkg 0402  page 52 : 1 = P3V3_AUX ; 2 = GND
C241  Q_CAP  0.1UF 25V 10% X7R  pkg 0402  page 51 : 1 = P12V_AUX ; 2 = GND
C242  Q_CAP  0.1UF 25V 10% X7R  pkg 0402  page 41 : 1 = VCCIO0 ; 2 = GND
C243  Q_CAP  0.1UF 25V 10% X7R  pkg 0402  page 41 : 1 = VCCIO1 ; 2 = GND
C244  Q_CAP  1UF 25V 10% X6S  pkg C0402  page 45 : 1 = P3V3_AUX ; 2 = GND
C245  Q_CAP  0.1UF 25V 10% X7R  pkg 0402  page 41 : 1 = VCCIO2 ; 2 = GND
C246  Q_CAP  0.01UF 50V 10% X7R  pkg C0402  page 45 : 1 = P3V3_AUX ; 2 = GND
C247  Q_CAP  0.1UF 25V 10% X7R  pkg 0402  page 41 : 1 = VCCIO0 ; 2 = GND
C248  Q_CAP  10UF 6.3V 20% X6S  pkg C0402  page 46 : 1 = P3V3_AUX ; 2 = GND
C249  Q_CAP  0.1UF 25V 10% X7R  pkg 0402  page 46 : 1 = P3V3_AUX ; 2 = GND
C250  Q_CAP  0.1UF 25V 10% X7R  pkg 0402  page 41 : 1 = PVCCA_AUX_PLD ; 2 = GND
C251  Q_CAP  0.1UF 25V 10% X7R  pkg 0402  page 52 : 1 = P3V3_RGM ; 2 = GND
C252  Q_CAP  1UF 25V 10% EMPTY  pkg C0402  page 52 : 1 = PWRGD_P3V3_RGM_R ; 2 = GND
C253  Q_CAP  0.1UF 25V 10% X7R  pkg 0402  page 22 : 1 = P3V3_AUX ; 2 = GND
C254  Q_CAP  0.1UF 25V 10% X7R  pkg 0402  page 41 : 1 = VCCIO1 ; 2 = GND
C255  Q_CAP  0.1UF 25V 10% X7R  pkg 0402  page 44 : 1 = P3V3_AUX ; 2 = GND
C256  Q_CAP  1UF 25V 10% X6S  pkg C0402  page 34 : 1 = PVCCIO_AUX_PLD ; 2 = GND
C257  Q_CAP  0.1UF 25V 10% X7R  pkg 0402  page 34 : 1 = PVCCIO_AUX_PLD ; 2 = GND
C260  Q_CAP  0.1UF 25V 10% X7R  pkg 0402  page 41 : 1 = VCCIO2 ; 2 = GND
C261  Q_CAP  0.1UF 25V 10% X7R  pkg 0402  page 41 : 1 = VCCIO0 ; 2 = GND
C262  Q_CAP  0.1UF 25V 10% X7R  pkg 0402  page 52 : 1 = P12V_AUX ; 2 = GND
C263  Q_CAP  0.1UF 25V 10% X7R  pkg 0402  page 41 : 1 = PVCCA_AUX_PLD ; 2 = GND
C264  Q_CAP  0.1UF 25V 10% X7R  pkg 0402  page 22 : 1 = U43_CT ; 2 = GND
C265  Q_CAP  22UF 16V 20% X6S  pkg C0805  page 52 : 1 = SW_P3V3_AUX_FLT ; 2 = GND
C266  Q_CAP  0.1UF 25V 10% X7R  pkg 0402  page 41 : 1 = PVCCA_AUX_PLD ; 2 = GND
C267  Q_CAP  1UF 16V 10% EMPTY  pkg 0402  page 27 : 1 = LPC_ESPI_SEL_R1 ; 2 = GND
C268  Q_CAP  0.1UF 25V 10% X7R  pkg 0402  page 30 : 1 = P3V3_AUX ; 2 = GND
C269  Q_CAP  0.1UF 25V 10% X7R  pkg 0402  page 41 : 1 = PVCCA_AUX_PLD ; 2 = GND
C270  Q_CAP  1UF 16V 10% EMPTY  pkg 0402  page 17 : 1 = LPC_ESPI_SEL_N ; 2 = GND
C271  Q_CAP  0.1UF 25V 10% X7R  pkg 0402  page 12 : 1 = P2E_GPU_TX_DN ; 2 = P2E_GPU_TX_C_DN
C272  Q_CAP  0.1UF 25V 10% X7R  pkg 0402  page 12 : 1 = P2E_GPU_TX_DP ; 2 = P2E_GPU_TX_C_DP
C273  Q_CAP  1UF 16V 10% EMPTY  pkg 0402  page 17 : 1 = LPC_ESPI_SEL_R ; 2 = GND
C274  Q_CAP  0.1UF 25V 10% X7R  pkg 0402  page 49 : 1 = P3V3_AUX ; 2 = GND
C275  Q_CAP  100PF 50V 5% NPO  pkg 0402  page 15 : 1 = P3V_BAT_SENSOR ; 2 = GND
C276  Q_CAP  0.1UF 25V 10% X7R  pkg 0402  page 49 : 1 = P3V3_AUX ; 2 = GND
C277  Q_CAP  1UF 25V 10% X6S  pkg C0402  page 17 : 1 = ADCVREFEXT1 ; 2 = GND
C278  Q_CAP  0.1UF 25V 10% X7R  pkg 0402  page 55 : 1 = P12V_AUX ; 2 = GND
C279  Q_CAP  0.1UF 25V 10% X7R  pkg 0402  page 17 : 1 = ADCVREFEXT1 ; 2 = GND
C280  Q_CAP  0.1UF 25V 10% X7R  pkg 0402  page 56 : 1 = P12V_AUX ; 2 = GND
C281  Q_CAP  0.01UF 50V 10% EMPTY  pkg C0402  page 41 : 1 = VCCIO1 ; 2 = GND
C282  Q_CAP  1UF 25V 10% X6S  pkg C0402  page 17 : 1 = ADCVREFEXT0 ; 2 = GND
C283  Q_CAP  0.01UF 50V 10% EMPTY  pkg C0402  page 41 : 1 = VCCIO0 ; 2 = GND
C284  Q_CAP  0.1UF 25V 10% X7R  pkg 0402  page 17 : 1 = ADCVREFEXT0 ; 2 = GND
C285  Q_CAP  0.01UF 50V 10% EMPTY  pkg C0402  page 41 : 1 = VCCIO2 ; 2 = GND
C286  Q_CAP  0.01UF 50V 10% EMPTY  pkg C0402  page 41 : 1 = PVCCA_AUX_PLD ; 2 = GND
C287  Q_CAP  1UF 25V 10% X6S  pkg C0402  page 53 : 1 = P5V_AUX ; 2 = GND
C288  Q_CAP  10UF 25V 10% X6S  pkg C0805  page 53 : 1 = P3V3_AUX ; 2 = GND
C289  Q_CAP  10UF 25V 10% X6S  pkg C0805  page 53 : 1 = P2V5_AUX ; 2 = GND
C290  Q_CAP  0.1UF 25V 10% X7R  pkg 0402  page 15 : 1 = P12V_SENSOR ; 2 = GND
C291  Q_CAP  0.1UF 25V 10% X7R  pkg 0402  page 53 : 1 = P2V5_AUX ; 2 = GND
C292  Q_CAP  1UF 25V 10% X6S  pkg C0402  page 54 : 1 = P5V_AUX ; 2 = GND
C293  Q_CAP  10UF 25V 10% X6S  pkg C0805  page 54 : 1 = P3V3_AUX ; 2 = GND
C294  Q_CAP  0.1UF 25V 10% X7R  pkg 0402  page 54 : 1 = P1V8_AUX ; 2 = GND
C295  Q_CAP  0.1UF 25V 10% X7R  pkg 0402  page 15 : 1 = P5V_SENSOR ; 2 = GND
C296  Q_CAP  0.1UF 25V 10% X7R  pkg 0402  page 52 : 1 = P3V3_LDO ; 2 = GND
C297  Q_CAP  0.1UF 25V 10% X7R  pkg 0402  page 52 : 1 = P3V3_LDO ; 2 = GND
C298  Q_CAP  0.1UF 25V 10% X7R  pkg 0402  page 54 : 1 = P3V3_LDO ; 2 = GND
C299  Q_CAP  0.1UF 25V 10% X7R  pkg 0402  page 15 : 1 = P3V3_SENSOR ; 2 = GND
C300  Q_CAP  0.1UF 25V 10% X7R  pkg 0402  page 28 : 1 = P3V3_AUX ; 2 = GND
C301  Q_CAP  0.1UF 25V 10% X7R  pkg 0402  page 55 : 1 = P3V3_LDO ; 2 = GND
C302  Q_CAP  0.1UF 25V 10% X7R  pkg 0402  page 56 : 1 = P3V3_LDO ; 2 = GND
C303  Q_CAP  0.1UF 25V 10% X7R  pkg 0402  page 15 : 1 = P2V5_SENSOR ; 2 = GND
C304  Q_CAP  0.1UF 25V 10% X7R  pkg 0402  page 25 : 1 = P3V3_AUX ; 2 = GND
C305  Q_CAP  1UF 25V 10% X6S  pkg C0402  page 52 : 1 = PWRGD_P1V8_AUX_R2 ; 2 = GND
C307  Q_CAP  0.1UF 25V 10% X7R  pkg 0402  page 15 : 1 = P1V8_SENSOR ; 2 = GND
C309  Q_CAP  0.1UF 25V 10% X7R  pkg 0402  page 15 : 1 = P1V2_SENSOR ; 2 = GND
C310  Q_CAP  1UF 25V 10% X6S  pkg C0402  page 54 : 1 = PWRGD_P3V3_RGM_R2 ; 2 = GND
C311  Q_CAP  0.1UF 25V 10% X7R  pkg 0402  page 15 : 1 = P1V0_SENSOR ; 2 = GND
C312  Q_CAP  0.1UF 25V 10% X7R  pkg 0402  page 25 : 1 = P3V3_AUX ; 2 = GND
C313  Q_CAP  0.1UF 25V 10% X7R  pkg 0402  page 25 : 1 = P3V3_AUX ; 2 = GND
C314  Q_CAP  0.1UF 25V 10% X7R  pkg 0402  page 15 : 1 = PGPPA_BMC_AUX_SENSOR ; 2 = GND
C318  Q_CAP  0.1UF 25V 10% X7R  pkg 0402  page 34 : 1 = P3V3_AUX ; 2 = GND
C321  Q_CAP  0.1UF 25V 10% X7R  pkg 0402  page 49 : 1 = PWR_LED_P5V_AUX ; 2 = GND
C324  Q_CAP  470PF 50V 10% X7R  pkg 0402  page 49 : 1 = HDD_LED_BUF_R ; 2 = GND
C326  Q_CAP  470PF 50V 10% X7R  pkg 0402  page 49 : 1 = PWR_LED_BUF_N_R ; 2 = GND
C327  Q_CAP  47UF 6.3V 20% X6S  pkg C1206  page 29 : 1 = P5V_USB_REAR ; 2 = GND
C329  Q_CAP  22UF 16V 20% X6S  pkg C0805  page 10 : 1 = P12V_AUX ; 2 = GND
C330  Q_CAP  22UF 16V 20% X6S  pkg C0805  page 10 : 1 = P12V_AUX ; 2 = GND
C335  Q_CAP  1UF 25V 10% X6S  pkg C0402  page 50 : 1 = REAR_AC_PWR_BMC_BTN_N ; 2 = GND
C336  Q_CAP  0.1UF 25V 10% X7R  pkg 0402  page 50 : 1 = P3V3_AUX ; 2 = GND
C337  Q_CAP  0.1UF 25V 10% X7R  pkg 0402  page 22 : 1 = P3V3_AUX ; 2 = GND
C500  Q_CAP  0.1UF 25V 10% X7R  pkg 0402  page 31 : 1 = P3V3_AUX ; 2 = GND
C501  Q_CAP  0.1UF 25V 10% X7R  pkg 0402  page 31 : 1 = P3V3_AUX ; 2 = GND
D0  Q_LED  IC  pkg SMLF  page 47 : A = LED_POSTCODE_0_R ; C = GND
D1  Q_LED  IC  pkg SMLF  page 47 : A = LED_POSTCODE_1_R ; C = GND
D2  Q_LED  IC  pkg SMLF  page 47 : A = LED_POSTCODE_2_R ; C = GND
D3  Q_LED  IC  pkg SMLF  page 47 : A = LED_POSTCODE_3_R ; C = GND
D4  Q_LED  IC  pkg SMLF  page 47 : A = LED_POSTCODE_4_R ; C = GND
D5  Q_LED  IC  pkg SMLF  page 47 : A = LED_POSTCODE_5_R ; C = GND
D6  Q_LED  IC  pkg SMLF  page 47 : A = LED_POSTCODE_6_R ; C = GND
D7  Q_LED  IC  pkg SMLF  page 47 : A = LED_POSTCODE_7_R ; C = GND
D8  Q_LED  IC  pkg SMLF  page 13 : A = BMC_HEARTBEAT_R_N ; C = BMC_HEARTBEAT_N
D9  SCHOTTKY_AC  SS0530 EMPTY  pkg SOD123XD  page 23 : A = P5V_AUX ; C = CRT_VCC5
D10  DIODE_BIDIRECTIONAL  UCLAMP0511T IC  pkg SLP1006P2T  page 50 : A = REAR_AC_PWR_BTN ; C = GND
D11  SCHOTTKY_AC  SS0530 IC  pkg SOD123XD  page 23 : A = P5V_AUX ; C = CRT_VCC5

D12  BZA462A  EMPTY  pkg SOT457XA  page 23
  1  \1\  BI  = CRT_VCC5
  2  \2\  BI  = GND
  3  \3\  BI  = CRT_VCC5
  4  \4\  BI  = CRT_VCC5
  5  \5\  BI  = GND
  6  \6\  BI  = CRT_VCC5

D13  Q_LED  IC  pkg THLF  page 49 : A = ID_LED_P3V3_AUX ; C = ID_LED_D_P3V3_AUX
D14  Q_LED  IC  pkg THLF  page 49 : A = PWR_LED_P5V_AUX ; C = PWR_LED_BUF_N_R
D15  Q_LED  IC  pkg THLF  page 49 : A = HDD_LED_P5V_AUX ; C = HDD_LED_BUF_R
D16  SCHOTTKY_12  SBA130Q EMPTY  pkg DFN1610-2_1-6X1  page 23 : 1 = P5V_AUX ; 2 = CRT_VCC5_2_D
D17  Q_DIODE  SDMK0340L-7-F IC  pkg SMLF  page 22 : 1 = RST_BMC_HW_OUT ; 2 = RST_BMC_SELF_HW_D
D18  Q_LED  IC  pkg SMLF  page 49 : A = P3V3_AUX ; C = FM_UARTSW_LSB_R1_N
D19  Q_LED  IC  pkg SMLF  page 49 : A = P3V3_AUX ; C = FM_UARTSW_MSB_R1_N
D20  SCHOTTKY_12  1N5819HW IC  pkg SOD123  page 32 : 1 = P3V3_AUX ; 2 = J7_P1
D21  Q_LED  IC  pkg THLF  page 50 : A = LED_D21_R3 ; C = GND
D22  Q_LED  IC  pkg THLF  page 50 : A = LED_D22_R ; C = LED_D22_R1
D23  Q_DIODE  SDMK0340L-7-F EMPTY  pkg SMLF  page 35 : 1 = PWRGD_P5V_AUX ; 2 = PWRGD_P5V_AUX_R1

DB1  TDR_3P  EMPTY  pkg TH2  page 60
  1  GND  UNSPEC  = T_GND
  2  IO1  UNSPEC  = TDR_SE_50_OHM_TOP
  3  IO2  UNSPEC  = TDR_SE_50_OHM_TOP

DB2  TDR_3P  EMPTY  pkg TH2  page 60
  1  GND  UNSPEC  = T_GND
  2  IO1  UNSPEC  = TDR_SE_50_OHM_IN1
  3  IO2  UNSPEC  = TDR_SE_50_OHM_IN1

DB3  TDR_3P  EMPTY  pkg TH2  page 60
  1  GND  UNSPEC  = T_GND
  2  IO1  UNSPEC  = TDR_SE_50_OHM_IN2
  3  IO2  UNSPEC  = TDR_SE_50_OHM_IN2

DB4  TDR_3P  EMPTY  pkg TH2  page 60
  1  GND  UNSPEC  = T_GND
  2  IO1  UNSPEC  = TDR_SE_50_OHM_IN3
  3  IO2  UNSPEC  = TDR_SE_50_OHM_IN3

DB5  TDR_3P  EMPTY  pkg TH2  page 60
  1  GND  UNSPEC  = T_GND
  2  IO1  UNSPEC  = TDR_SE_50_OHM_IN4
  3  IO2  UNSPEC  = TDR_SE_50_OHM_IN4

DB6  TDR_3P  EMPTY  pkg TH2  page 60
  1  GND  UNSPEC  = T_GND
  2  IO1  UNSPEC  = TDR_SE_50_OHM_BOT
  3  IO2  UNSPEC  = TDR_SE_50_OHM_BOT

DM1  DUMMY_SYMBOL  BMC_FLASH EMPTY  pkg TP30_FOR_BOM  page 59 : 1 = NC
DM2  DUMMY_SYMBOL  BMC_FLASH EMPTY  pkg TP30_FOR_BOM  page 59 : 1 = NC
DM3  DUMMY_SYMBOL  BIOS_FLASH MECH  pkg TP30_FOR_BOM  page 59 : 1 = NC
DM7  ME_DUMMY_SYMBOL  PB-E1_SMALL EMPTY  pkg PB-E1_SMALL  page 59
FS1  Q_FUSE  1.1A/8V EMPTY  pkg SMLF  page 23 : 1 = CRT_VCC5_2_D ; 2 = CRT_VCC5_2_FUSE
